# T6G (Grand Teton) — schematic netlist excerpt (pin names and nets, part order shuffled) for the footprints in the layout excerpt that follows; sources: Cadence DE-HDL packaged netlist, KiCad conversion of 04192023_DAF0TMB3IC0_F0TG_MB_C_brd_V02_OCP.brd

R3523  Q_RES  54.9K 1% CHIP  pkg 0402LF  page 248 : A = P3V3_AUX ; B = SMB_1_BMC_GPU_BUF_R_SCL
PC126_C0P1_6  Q_CAP  2.2UF 10V 10% X6S  pkg C0402  page 213 : A = PVDDCR_CPU0_P1_PVCC ; B = GND
C2077  Q_CAP_DIFFBUS  DIFF BUS_0.22UF 6.3V 20% X6S  pkg C0201  page 26 : \1\ = P2E_CPU0_P5_TX_DP ; \2\ = P2E_CPU0_P5_TX_C_DP

(kicad_pcb
	(version 20260206)
	(generator "pcbnew")
	(generator_version "10.0")
	(general
		(thickness 1.6)
		(legacy_teardrops no)
	)
	(paper "A4")
	(title_block
		(title "04192023_DAF0TMB3IC0_F0TG_MB_C_brd_V02_OCP.brd")
		(comment 1 "Grand Teton / footprints 2294-2296 of 8354")
	)
	(layers
		(0 "F.Cu" signal "TOP")
		(4 "In1.Cu" signal "GND")
		(6 "In2.Cu" signal "IN1")
		(8 "In3.Cu" signal "GND1")
		(10 "In4.Cu" signal "IN2")
		(12 "In5.Cu" signal "GND2")
		(14 "In6.Cu" signal "IN3")
		(16 "In7.Cu" signal "GND3")
		(18 "In8.Cu" signal "VCC")
		(20 "In9.Cu" signal "VCC1")
		(22 "In10.Cu" signal "GND4")
		(24 "In11.Cu" signal "IN4")
		(26 "In12.Cu" signal "GND5")
		(28 "In13.Cu" signal "IN5")
		(30 "In14.Cu" signal "GND6")
		(32 "In15.Cu" signal "IN6")
		(34 "In16.Cu" signal "GND7")
		(2 "B.Cu" signal "BOTTOM")
		(9 "F.Adhes" user "F.Adhesive")
		(11 "B.Adhes" user "B.Adhesive")
		(13 "F.Paste" user "Package Geometry/Pastemask Top")
		(15 "B.Paste" user "Package Geometry/Pastemask Bottom")
		(5 "F.SilkS" user "Ref Des/Silkscreen Top")
		(7 "B.SilkS" user "Ref Des/Silkscreen Bottom")
		(1 "F.Mask" user "Board Geometry/Soldermask Top")
		(3 "B.Mask" user "Board Geometry/Soldermask Bottom")
		(17 "Dwgs.User" user "User.Drawings")
		(19 "Cmts.User" user "User.Comments")
		(21 "Eco1.User" user "User.Eco1")
		(23 "Eco2.User" user "User.Eco2")
		(25 "Edge.Cuts" user "Board Geometry/Outline")
		(27 "Margin" user)
		(31 "F.CrtYd" user "Package Geometry/Place Bound Top")
		(29 "B.CrtYd" user "Package Geometry/Place Bound Bottom")
		(35 "F.Fab" user "Ref Des/Assembly Top")
		(33 "B.Fab" user "Ref Des/Assembly Bottom")
	)
	(footprint ""
		(layer "F.Cu")
		(at 22.07768 -432.437794)
		(property "Reference" "R3523"
			(at 0 0 0)
			(layer "F.SilkS")
			(hide yes)
			(effects
				(font
					(size 1.27 1.27)
				)
			)
		)
		(property "Value" ""
			(at 0 0 0)
			(layer "F.Fab")
			(effects
				(font
					(size 1.27 1.27)
				)
			)
		)
		(duplicate_pad_numbers_are_jumpers no)
		(fp_line
			(start -0.7874 -0.4064)
			(end 0.7874 -0.4064)
			(stroke
				(width 0.1524)
				(type default)
			)
			(layer "F.SilkS")
		)
		(fp_line
			(start -0.7874 0.4064)
			(end -0.7874 -0.4064)
			(stroke
				(width 0.1524)
				(type default)
			)
			(layer "F.SilkS")
		)
		(fp_line
			(start 0.7874 -0.4064)
			(end 0.7874 0.4064)
			(stroke
				(width 0.1524)
				(type default)
			)
			(layer "F.SilkS")
		)
		(fp_line
			(start 0.7874 0.4064)
			(end -0.7874 0.4064)
			(stroke
				(width 0.1524)
				(type default)
			)
			(layer "F.SilkS")
		)
		(fp_line
			(start -0.67945 -0.305054)
			(end -0.12065 -0.305054)
			(stroke
				(width 0.1)
				(type default)
			)
			(layer "F.Fab")
		)
		(fp_line
			(start -0.67945 0.3048)
			(end -0.67945 -0.305054)
			(stroke
				(width 0.1)
				(type default)
			)
			(layer "F.Fab")
		)
		(fp_line
			(start -0.12065 -0.305054)
			(end -0.12065 -0.2794)
			(stroke
				(width 0.1)
				(type default)
			)
			(layer "F.Fab")
		)
		(fp_line
			(start -0.12065 -0.2794)
			(end 0.12065 -0.2794)
			(stroke
				(width 0.1)
				(type default)
			)
			(layer "F.Fab")
		)
		(fp_line
			(start -0.12065 0.2794)
			(end -0.12065 0.3048)
			(stroke
				(width 0.1)
				(type default)
			)
			(layer "F.Fab")
		)
		(fp_line
			(start -0.12065 0.3048)
			(end -0.67945 0.3048)
			(stroke
				(width 0.1)
				(type default)
			)
			(layer "F.Fab")
		)
		(fp_line
			(start 0.120396 0.2794)
			(end -0.12065 0.2794)
			(stroke
				(width 0.1)
				(type default)
			)
			(layer "F.Fab")
		)
		(fp_line
			(start 0.120396 0.3048)
			(end 0.120396 0.2794)
			(stroke
				(width 0.1)
				(type default)
			)
			(layer "F.Fab")
		)
		(fp_line
			(start 0.12065 -0.3048)
			(end 0.67945 -0.3048)
			(stroke
				(width 0.1)
				(type default)
			)
			(layer "F.Fab")
		)
		(fp_line
			(start 0.12065 -0.2794)
			(end 0.12065 -0.3048)
			(stroke
				(width 0.1)
				(type default)
			)
			(layer "F.Fab")
		)
		(fp_line
			(start 0.67945 -0.3048)
			(end 0.67945 0.3048)
			(stroke
				(width 0.1)
				(type default)
			)
			(layer "F.Fab")
		)
		(fp_line
			(start 0.67945 0.3048)
			(end 0.120396 0.3048)
			(stroke
				(width 0.1)
				(type default)
			)
			(layer "F.Fab")
		)
		(pad "1" smd circle
			(at -0.40005 0)
			(size 0 0)
			(layers "F.Cu" "F.Mask" "F.Paste")
			(net "P3V3_AUX")
		)
		(pad "2" smd circle
			(at 0.40005 0)
			(size 0 0)
			(layers "F.Cu" "F.Mask" "F.Paste")
			(net "SMB_1_BMC_GPU_BUF_R_SCL")
		)
	)
	(footprint ""
		(layer "F.Cu")
		(at 160.057338 -20.068794 -90)
		(property "Reference" "C2077"
			(at 0 0 270)
			(layer "F.SilkS")
			(hide yes)
			(effects
				(font
					(size 1.27 1.27)
				)
			)
		)
		(property "Value" ""
			(at 0 0 270)
			(layer "F.Fab")
			(effects
				(font
					(size 1.27 1.27)
				)
			)
		)
		(duplicate_pad_numbers_are_jumpers no)
		(fp_line
			(start -0.299974 0.150114)
			(end -0.299974 -0.150114)
			(stroke
				(width 0.1)
				(type default)
			)
			(layer "F.Fab")
		)
		(fp_line
			(start 0.299974 0.150114)
			(end -0.299974 0.150114)
			(stroke
				(width 0.1)
				(type default)
			)
			(layer "F.Fab")
		)
		(fp_line
			(start -0.299974 -0.150114)
			(end 0.299974 -0.150114)
			(stroke
				(width 0.1)
				(type default)
			)
			(layer "F.Fab")
		)
		(fp_line
			(start 0.299974 -0.150114)
			(end 0.299974 0.150114)
			(stroke
				(width 0.1)
				(type default)
			)
			(layer "F.Fab")
		)
		(pad "1" smd rect
			(at -0.2667 0 270)
			(size 0.3048 0.381)
			(layers "F.Cu" "F.Mask" "F.Paste")
			(net "P2E_CPU0_P5_TX_DP")
		)
		(pad "2" smd rect
			(at 0.2667 0 270)
			(size 0.3048 0.381)
			(layers "F.Cu" "F.Mask" "F.Paste")
			(net "P2E_CPU0_P5_TX_C_DP")
		)
	)
	(footprint ""
		(layer "F.Cu")
		(at 69.33057 -168.93032 90)
		(property "Reference" "PC126_C0P1_6"
			(at 0 0 90)
			(layer "F.SilkS")
			(hide yes)
			(effects
				(font
					(size 1.27 1.27)
				)
			)
		)
		(property "Value" ""
			(at 0 0 90)
			(layer "F.Fab")
			(effects
				(font
					(size 1.27 1.27)
				)
			)
		)
		(duplicate_pad_numbers_are_jumpers no)
		(fp_line
			(start 0.7874 -0.4064)
			(end 0.7874 0.4064)
			(stroke
				(width 0.1524)
				(type default)
			)
			(layer "F.SilkS")
		)
		(fp_line
			(start -0.7874 -0.4064)
			(end 0.7874 -0.4064)
			(stroke
				(width 0.1524)
				(type default)
			)
			(layer "F.SilkS")
		)
		(fp_line
			(start 0.7874 0.4064)
			(end -0.7874 0.4064)
			(stroke
				(width 0.1524)
				(type default)
			)
			(layer "F.SilkS")
		)
		(fp_line
			(start -0.7874 0.4064)
			(end -0.7874 -0.4064)
			(stroke
				(width 0.1524)
				(type default)
			)
			(layer "F.SilkS")
		)
		(fp_line
			(start -0.12065 -0.305054)
			(end -0.12065 -0.2794)
			(stroke
				(width 0.1)
				(type default)
			)
			(layer "F.Fab")
		)
		(fp_line
			(start -0.67945 -0.305054)
			(end -0.12065 -0.305054)
			(stroke
				(width 0.1)
				(type default)
			)
			(layer "F.Fab")
		)
		(fp_line
			(start 0.67945 -0.3048)
			(end 0.67945 0.3048)
			(stroke
				(width 0.1)
				(type default)
			)
			(layer "F.Fab")
		)
		(fp_line
			(start 0.12065 -0.3048)
			(end 0.67945 -0.3048)
			(stroke
				(width 0.1)
				(type default)
			)
			(layer "F.Fab")
		)
		(fp_line
			(start 0.12065 -0.2794)
			(end 0.12065 -0.3048)
			(stroke
				(width 0.1)
				(type default)
			)
			(layer "F.Fab")
		)
		(fp_line
			(start -0.12065 -0.2794)
			(end 0.12065 -0.2794)
			(stroke
				(width 0.1)
				(type default)
			)
			(layer "F.Fab")
		)
		(fp_line
			(start 0.120396 0.2794)
			(end -0.12065 0.2794)
			(stroke
				(width 0.1)
				(type default)
			)
			(layer "F.Fab")
		)
		(fp_line
			(start -0.12065 0.2794)
			(end -0.12065 0.3048)
			(stroke
				(width 0.1)
				(type default)
			)
			(layer "F.Fab")
		)
		(fp_line
			(start 0.67945 0.3048)
			(end 0.120396 0.3048)
			(stroke
				(width 0.1)
				(type default)
			)
			(layer "F.Fab")
		)
		(fp_line
			(start 0.120396 0.3048)
			(end 0.120396 0.2794)
			(stroke
				(width 0.1)
				(type default)
			)
			(layer "F.Fab")
		)
		(fp_line
			(start -0.12065 0.3048)
			(end -0.67945 0.3048)
			(stroke
				(width 0.1)
				(type default)
			)
			(layer "F.Fab")
		)
		(fp_line
			(start -0.67945 0.3048)
			(end -0.67945 -0.305054)
			(stroke
				(width 0.1)
				(type default)
			)
			(layer "F.Fab")
		)
		(pad "1" smd circle
			(at -0.40005 0 90)
			(size 0 0)
			(layers "F.Cu" "F.Mask" "F.Paste")
			(net "PVDDCR_CPU0_P1_PVCC")
		)
		(pad "2" smd circle
			(at 0.40005 0 90)
			(size 0 0)
			(layers "F.Cu" "F.Mask" "F.Paste")
			(net "GND")
		)
	)
)
